(kicad_pcb
	(version 20260206)
	(generator "pcbnew")
	(generator_version "10.0")
	(general
		(thickness 1.6)
		(legacy_teardrops no)
	)
	(paper "A4")
	(title_block
		(title "Wiwynn_Tioga_Pass_MB.brd")
		(comment 1 "Tioga Pass / footprints 866-867 of 4770")
	)
	(layers
		(0 "F.Cu" signal "TOP")
		(4 "In1.Cu" signal "L2GND")
		(6 "In2.Cu" signal "L3")
		(8 "In3.Cu" signal "L4GND")
		(10 "In4.Cu" signal "L5")
		(12 "In5.Cu" signal "L6GND")
		(14 "In6.Cu" signal "L7VCC")
		(16 "In7.Cu" signal "L8VCC")
		(18 "In8.Cu" signal "L9GND")
		(20 "In9.Cu" signal "L10")
		(22 "In10.Cu" signal "L11GND")
		(24 "In11.Cu" signal "L12")
		(26 "In12.Cu" signal "L13GND")
		(2 "B.Cu" signal "BOTTOM")
		(9 "F.Adhes" user "F.Adhesive")
		(11 "B.Adhes" user "B.Adhesive")
		(13 "F.Paste" user "Package Geometry/Pastemask Top")
		(15 "B.Paste" user "Package Geometry/Pastemask Bottom")
		(5 "F.SilkS" user "Ref Des/Silkscreen Top")
		(7 "B.SilkS" user "Ref Des/Silkscreen Bottom")
		(1 "F.Mask" user "Board Geometry/Soldermask Top")
		(3 "B.Mask" user "Board Geometry/Soldermask Bottom")
		(17 "Dwgs.User" user "User.Drawings")
		(19 "Cmts.User" user "User.Comments")
		(21 "Eco1.User" user "User.Eco1")
		(23 "Eco2.User" user "User.Eco2")
		(25 "Edge.Cuts" user "Board Geometry/Outline")
		(27 "Margin" user)
		(31 "F.CrtYd" user "Package Geometry/Place Bound Top")
		(29 "B.CrtYd" user "Package Geometry/Place Bound Bottom")
		(35 "F.Fab" user "Ref Des/Assembly Top")
		(33 "B.Fab" user "Ref Des/Assembly Bottom")
	)
	(footprint ""
		(layer "F.Cu")
		(at 175.387 -76.327 90)
		(property "Reference" "R4D29"
			(at 0 0 90)
			(layer "F.SilkS")
			(hide yes)
			(effects
				(font
					(size 1.27 1.27)
				)
			)
		)
		(property "Value" ""
			(at 0 0 90)
			(layer "F.Fab")
			(effects
				(font
					(size 1.27 1.27)
				)
			)
		)
		(duplicate_pad_numbers_are_jumpers no)
		(fp_poly
			(pts
				(xy -0.2794 -0.1016) (xy 0.2794 -0.1016) (xy 0.2794 0.9906) (xy -0.2794 0.9906)
			)
			(stroke
				(width 0)
				(type default)
			)
			(fill no)
			(layer "F.CrtYd")
		)
		(fp_line
			(start 0.2794 -0.1016)
			(end -0.2794 -0.1016)
			(stroke
				(width 0.1)
				(type default)
			)
			(layer "F.Fab")
		)
		(fp_line
			(start -0.2794 -0.1016)
			(end -0.2794 0.9906)
			(stroke
				(width 0.1)
				(type default)
			)
			(layer "F.Fab")
		)
		(fp_line
			(start 0.2794 0.9906)
			(end 0.2794 -0.1016)
			(stroke
				(width 0.1)
				(type default)
			)
			(layer "F.Fab")
		)
		(fp_line
			(start -0.2794 0.9906)
			(end 0.2794 0.9906)
			(stroke
				(width 0.1)
				(type default)
			)
			(layer "F.Fab")
		)
		(pad "1" smd rect
			(at 0 0 90)
			(size 0.508 0.508)
			(layers "F.Cu" "F.Mask" "F.Paste")
			(net "CLK_100M_CPU0_BCLK0_R_DP")
		)
		(pad "2" smd rect
			(at 0 0.889 90)
			(size 0.508 0.508)
			(layers "F.Cu" "F.Mask" "F.Paste")
			(net "CLK_100M_CPU0_BCLK0_DP")
		)
		(zone
			(layer "F.Cu")
			(hatch none 0.5)
			(connect_pads
				(clearance 0)
			)
			(min_thickness 0.25)
			(keepout
				(tracks allowed)
				(vias not_allowed)
				(pads allowed)
				(copperpour not_allowed)
				(footprints allowed)
			)
			(placement
				(enabled no)
				(sheetname "")
			)
			(fill
				(thermal_gap 0.5)
				(thermal_bridge_width 0.5)
				(island_removal_mode 0)
			)
			(polygon
				(pts
					(xy 175.641 -76.073) (xy 175.641 -76.581) (xy 176.022 -76.581) (xy 176.022 -76.073)
				)
			)
		)
		(zone
			(layer "F.Cu")
			(hatch none 0.5)
			(connect_pads
				(clearance 0)
			)
			(min_thickness 0.25)
			(keepout
				(tracks not_allowed)
				(vias allowed)
				(pads allowed)
				(copperpour not_allowed)
				(footprints allowed)
			)
			(placement
				(enabled no)
				(sheetname "")
			)
			(fill
				(thermal_gap 0.5)
				(thermal_bridge_width 0.5)
				(island_removal_mode 0)
			)
			(polygon
				(pts
					(xy 176.022 -76.073) (xy 176.022 -76.581) (xy 175.641 -76.581) (xy 175.641 -76.073)
				)
			)
		)
	)
	(footprint ""
		(layer "F.Cu")
		(at 462.980532 -135.71982 90.001)
		(property "Reference" "J9A3"
			(at 3.15304 -8.221925 90.001)
			(unlocked yes)
			(layer "F.SilkS")
			(effects
				(font
					(size 0.7874 0.5842)
					(thickness 0.1524)
				)
				(justify left)
			)
		)
		(property "Value" ""
			(at 0 0 90.001)
			(layer "F.Fab")
			(effects
				(font
					(size 1.27 1.27)
				)
			)
		)
		(duplicate_pad_numbers_are_jumpers no)
		(fp_line
			(start 14.981542 -6.508743)
			(end 16.939628 -6.508708)
			(stroke
				(width 0.1524)
				(type default)
			)
			(layer "F.SilkS")
		)
		(fp_line
			(start -2.146948 -6.508787)
			(end -0.473088 -6.508758)
			(stroke
				(width 0.1524)
				(type default)
			)
			(layer "F.SilkS")
		)
		(fp_line
			(start 17.911812 0.781109)
			(end 17.911906 -4.573465)
			(stroke
				(width 0.1524)
				(type default)
			)
			(layer "F.SilkS")
		)
		(fp_line
			(start 17.911812 0.781109)
			(end 14.973794 0.781057)
			(stroke
				(width 0.1524)
				(type default)
			)
			(layer "F.SilkS")
		)
		(fp_line
			(start -3.411742 0.78099)
			(end -3.411648 -4.59111)
			(stroke
				(width 0.1524)
				(type default)
			)
			(layer "F.SilkS")
		)
		(fp_line
			(start -3.411742 0.78099)
			(end -0.517412 0.781041)
			(stroke
				(width 0.1524)
				(type default)
			)
			(layer "F.SilkS")
		)
		(fp_poly
			(pts
				(xy -0.862117 2.348977) (xy 0.153883 2.348995) (xy -0.354095 1.078986)
			)
			(stroke
				(width 0)
				(type default)
			)
			(fill yes)
			(layer "F.SilkS")
		)
		(fp_poly
			(pts
				(xy -3.411741 -6.50881) (xy 17.911813 -6.508809) (xy 17.911812 0.780991) (xy -3.411742 0.78099)
			)
			(stroke
				(width 0)
				(type default)
			)
			(fill no)
			(layer "F.CrtYd")
		)
		(fp_line
			(start 17.91194 -6.508691)
			(end -3.411614 -6.50881)
			(stroke
				(width 0.1)
				(type default)
			)
			(layer "F.Fab")
		)
		(fp_line
			(start -3.411614 -6.50881)
			(end -3.411742 0.78099)
			(stroke
				(width 0.1)
				(type default)
			)
			(layer "F.Fab")
		)
		(fp_line
			(start 17.911812 0.781109)
			(end 17.91194 -6.508691)
			(stroke
				(width 0.1)
				(type default)
			)
			(layer "F.Fab")
		)
		(fp_line
			(start -3.411742 0.78099)
			(end 17.911812 0.781109)
			(stroke
				(width 0.1)
				(type default)
			)
			(layer "F.Fab")
		)
		(fp_poly
			(pts
				(xy -0.508302 2.770115) (xy 0.507698 2.770133) (xy -0.00028 1.500124)
			)
			(stroke
				(width 0)
				(type default)
			)
			(fill yes)
			(layer "F.Fab")
		)
		(fp_text user "60"
			(at 19.142806 -5.526204 0.001)
			(unlocked yes)
			(layer "F.SilkS")
			(effects
				(font
					(size 0.7874 0.5842)
					(thickness 0.1524)
				)
				(justify left)
			)
		)
		(fp_text user "2"
			(at -4.098208 -4.71381 0.001)
			(unlocked yes)
			(layer "F.SilkS")
			(effects
				(font
					(size 0.7874 0.5842)
					(thickness 0.1524)
				)
				(justify left)
			)
		)
		(fp_text user "59"
			(at -2.150904 1.508722 90.001)
			(unlocked yes)
			(layer "F.SilkS")
			(effects
				(font
					(size 0.7874 0.5842)
					(thickness 0.1524)
				)
				(justify left)
			)
		)
		(fp_text user "60"
			(at 18.363061 -7.479478 0.001)
			(unlocked yes)
			(layer "F.Fab")
			(effects
				(font
					(size 0.7874 0.5842)
					(thickness 0.1524)
				)
				(justify left)
			)
		)
		(fp_text user "2"
			(at -4.005214 -6.406972 0.001)
			(unlocked yes)
			(layer "F.Fab")
			(effects
				(font
					(size 0.7874 0.5842)
					(thickness 0.1524)
				)
				(justify left)
			)
		)
		(fp_text user "59"
			(at 14.926285 1.407923 0.001)
			(unlocked yes)
			(layer "F.Fab")
			(effects
				(font
					(size 0.7874 0.5842)
					(thickness 0.1524)
				)
				(justify left)
			)
		)
		(pad "" np_thru_hole circle
			(at -2.810002 -5.530088 90.001)
			(size 0.254 0.254)
			(drill 1.0414)
			(layers "*.Cu" "*.Mask")
			(clearance 0.7112)
			(thermal_gap 0.7112)
		)
		(pad "" np_thru_hole circle
			(at 17.315942 -5.530088 90.001)
			(size 0.254 0.254)
			(drill 1.0414)
			(layers "*.Cu" "*.Mask")
			(clearance 0.7112)
			(thermal_gap 0.7112)
		)
		(pad "1" smd rect
			(at 0 0 90.001)
			(size 0.2794 2.286)
			(layers "F.Cu" "F.Mask" "F.Paste")
			(net "XDP_DEBUG_CONSENT_N")
		)
		(pad "2" smd rect
			(at 0 -5.727954 90.001)
			(size 0.2794 2.286)
			(layers "F.Cu" "F.Mask" "F.Paste")
			(net "GND")
		)
		(pad "3" smd rect
			(at 0.500126 0 90.001)
			(size 0.2794 2.286)
			(layers "F.Cu" "F.Mask" "F.Paste")
			(net "XDP_PREQ_N")
		)
		(pad "4" smd rect
			(at 0.500126 -5.727954 90.001)
			(size 0.2794 2.286)
			(layers "F.Cu" "F.Mask" "F.Paste")
			(net "TP_XDP_CPU_OBSFN_C0")
		)
		(pad "5" smd rect
			(at 0.999998 0 90.001)
			(size 0.2794 2.286)
			(layers "F.Cu" "F.Mask" "F.Paste")
			(net "XDP_PRDY_N")
		)
		(pad "6" smd rect
			(at 0.999998 -5.727954 90.001)
			(size 0.2794 2.286)
			(layers "F.Cu" "F.Mask" "F.Paste")
			(net "XDP_SPI_PCH_MOSI_BOOT_HALT_N")
		)
		(pad "7" smd rect
			(at 1.500124 0 90.001)
			(size 0.2794 2.286)
			(layers "F.Cu" "F.Mask" "F.Paste")
			(net "GND")
		)
		(pad "8" smd rect
			(at 1.500124 -5.727954 90.001)
			(size 0.2794 2.286)
			(layers "F.Cu" "F.Mask" "F.Paste")
			(net "GND")
		)
		(pad "9" smd rect
			(at 1.999996 0 90.001)
			(size 0.2794 2.286)
			(layers "F.Cu" "F.Mask" "F.Paste")
			(net "TP_XDP_OBSDATA_A0")
		)
		(pad "10" smd rect
			(at 1.999996 -5.727954 90.001)
			(size 0.2794 2.286)
			(layers "F.Cu" "F.Mask" "F.Paste")
			(net "TP_XDP_CPU_OBSDATA_C0")
		)
		(pad "11" smd rect
			(at 2.500122 0 90.001)
			(size 0.2794 2.286)
			(layers "F.Cu" "F.Mask" "F.Paste")
			(net "TP_XDP_OBSDATA_A1")
		)
		(pad "12" smd rect
			(at 2.500122 -5.727954 90.001)
			(size 0.2794 2.286)
			(layers "F.Cu" "F.Mask" "F.Paste")
			(net "TP_XDP_CPU_OBSDATA_C1")
		)
		(pad "13" smd rect
			(at 2.999994 0 90.001)
			(size 0.2794 2.286)
			(layers "F.Cu" "F.Mask" "F.Paste")
			(net "GND")
		)
		(pad "14" smd rect
			(at 2.999994 -5.727954 90.001)
			(size 0.2794 2.286)
			(layers "F.Cu" "F.Mask" "F.Paste")
			(net "GND")
		)
		(pad "15" smd rect
			(at 3.50012 0 90.001)
			(size 0.2794 2.286)
			(layers "F.Cu" "F.Mask" "F.Paste")
			(net "TP_XDP_OBSDATA_A2")
		)
		(pad "16" smd rect
			(at 3.50012 -5.727954 90.001)
			(size 0.2794 2.286)
			(layers "F.Cu" "F.Mask" "F.Paste")
			(net "TP_XDP_CPU_OBSDATA_C2")
		)
		(pad "17" smd rect
			(at 3.999992 0 90.001)
			(size 0.2794 2.286)
			(layers "F.Cu" "F.Mask" "F.Paste")
			(net "TP_XDP_OBSDATA_A3")
		)
		(pad "18" smd rect
			(at 3.999992 -5.727954 90.001)
			(size 0.2794 2.286)
			(layers "F.Cu" "F.Mask" "F.Paste")
			(net "TP_XDP_CPU_OBSDATA_C3")
		)
		(pad "19" smd rect
			(at 4.500118 0 90.001)
			(size 0.2794 2.286)
			(layers "F.Cu" "F.Mask" "F.Paste")
			(net "GND")
		)
		(pad "20" smd rect
			(at 4.500118 -5.727954 90.001)
			(size 0.2794 2.286)
			(layers "F.Cu" "F.Mask" "F.Paste")
			(net "GND")
		)
		(pad "21" smd rect
			(at 4.99999 0 90.001)
			(size 0.2794 2.286)
			(layers "F.Cu" "F.Mask" "F.Paste")
			(net "TP_XDP_OBSFN_B0")
		)
		(pad "22" smd rect
			(at 4.99999 -5.727954 90.001)
			(size 0.2794 2.286)
			(layers "F.Cu" "F.Mask" "F.Paste")
			(net "XDP_OBSFN_B0_MBP6_N")
		)
		(pad "23" smd rect
			(at 5.500116 0 90.001)
			(size 0.2794 2.286)
			(layers "F.Cu" "F.Mask" "F.Paste")
			(net "TP_XDP_OBSFN_B1")
		)
		(pad "24" smd rect
			(at 5.500116 -5.727954 90.001)
			(size 0.2794 2.286)
			(layers "F.Cu" "F.Mask" "F.Paste")
			(net "XDP_OBSFN_B1_MBP7_N")
		)
		(pad "25" smd rect
			(at 5.999988 0 90.001)
			(size 0.2794 2.286)
			(layers "F.Cu" "F.Mask" "F.Paste")
			(net "GND")
		)
		(pad "26" smd rect
			(at 5.999988 -5.727954 90.001)
			(size 0.2794 2.286)
			(layers "F.Cu" "F.Mask" "F.Paste")
			(net "GND")
		)
		(pad "27" smd rect
			(at 6.500114 0 90.001)
			(size 0.2794 2.286)
			(layers "F.Cu" "F.Mask" "F.Paste")
			(net "TP_XDP_OBSDATA_B0")
		)
		(pad "28" smd rect
			(at 6.500114 -5.727954 90.001)
			(size 0.2794 2.286)
			(layers "F.Cu" "F.Mask" "F.Paste")
			(net "TP_XDP_CPU_OBSDATA_D0")
		)
		(pad "29" smd rect
			(at 6.999986 0 90.001)
			(size 0.2794 2.286)
			(layers "F.Cu" "F.Mask" "F.Paste")
			(net "TP_XDP_OBSDATA_B1")
		)
		(pad "30" smd rect
			(at 6.999986 -5.727954 90.001)
			(size 0.2794 2.286)
			(layers "F.Cu" "F.Mask" "F.Paste")
			(net "TP_XDP_CPU_OBSDATA_D1")
		)
		(pad "31" smd rect
			(at 7.500112 0 90.001)
			(size 0.2794 2.286)
			(layers "F.Cu" "F.Mask" "F.Paste")
			(net "GND")
		)
		(pad "32" smd rect
			(at 7.500112 -5.727954 90.001)
			(size 0.2794 2.286)
			(layers "F.Cu" "F.Mask" "F.Paste")
			(net "GND")
		)
		(pad "33" smd rect
			(at 7.999984 0 90.001)
			(size 0.2794 2.286)
			(layers "F.Cu" "F.Mask" "F.Paste")
			(net "TP_XDP_OBSDATA_B2")
		)
		(pad "34" smd rect
			(at 7.999984 -5.727954 90.001)
			(size 0.2794 2.286)
			(layers "F.Cu" "F.Mask" "F.Paste")
			(net "TP_XDP_CPU_OBSDATA_D2")
		)
		(pad "35" smd rect
			(at 8.50011 0 90.001)
			(size 0.2794 2.286)
			(layers "F.Cu" "F.Mask" "F.Paste")
			(net "TP_XDP_OBSDATA_B3")
		)
		(pad "36" smd rect
			(at 8.50011 -5.727954 90.001)
			(size 0.2794 2.286)
			(layers "F.Cu" "F.Mask" "F.Paste")
			(net "TP_XDP_CPU_OBSDATA_D3")
		)
		(pad "37" smd rect
			(at 8.999982 0 90.001)
			(size 0.2794 2.286)
			(layers "F.Cu" "F.Mask" "F.Paste")
			(net "GND")
		)
		(pad "38" smd rect
			(at 8.999982 -5.727954 90.001)
			(size 0.2794 2.286)
			(layers "F.Cu" "F.Mask" "F.Paste")
			(net "GND")
		)
		(pad "39" smd rect
			(at 9.500108 0 90.001)
			(size 0.2794 2.286)
			(layers "F.Cu" "F.Mask" "F.Paste")
			(net "XDP_RSMRST_N")
		)
		(pad "40" smd rect
			(at 9.500108 -5.727954 90.001)
			(size 0.2794 2.286)
			(layers "F.Cu" "F.Mask" "F.Paste")
			(net "CLK_100M_PCH_XDP_DP")
		)
		(pad "41" smd rect
			(at 9.99998 0 90.001)
			(size 0.2794 2.286)
			(layers "F.Cu" "F.Mask" "F.Paste")
			(net "XDP_PWRGD_RST_N")
		)
		(pad "42" smd rect
			(at 9.99998 -5.727954 90.001)
			(size 0.2794 2.286)
			(layers "F.Cu" "F.Mask" "F.Paste")
			(net "CLK_100M_PCH_XDP_DN")
		)
		(pad "43" smd rect
			(at 10.500106 0 90.001)
			(size 0.2794 2.286)
			(layers "F.Cu" "F.Mask" "F.Paste")
			(net "P1V05_PCH_STBY")
		)
		(pad "44" smd rect
			(at 10.500106 -5.727954 90.001)
			(size 0.2794 2.286)
			(layers "F.Cu" "F.Mask" "F.Paste")
			(net "P1V05_PCH_STBY")
		)
		(pad "45" smd rect
			(at 10.999978 0 90.001)
			(size 0.2794 2.286)
			(layers "F.Cu" "F.Mask" "F.Paste")
			(net "XDP_CPU_PWR_DEBUG_N")
		)
		(pad "46" smd rect
			(at 10.999978 -5.727954 90.001)
			(size 0.2794 2.286)
			(layers "F.Cu" "F.Mask" "F.Paste")
			(net "XDP_ITP_PMODE")
		)
		(pad "47" smd rect
			(at 11.500104 0 90.001)
			(size 0.2794 2.286)
			(layers "F.Cu" "F.Mask" "F.Paste")
			(net "XDP_SYSPWROK")
		)
		(pad "48" smd rect
			(at 11.500104 -5.727954 90.001)
			(size 0.2794 2.286)
			(layers "F.Cu" "F.Mask" "F.Paste")
			(net "XDP_RST_CO_N")
		)
		(pad "49" smd rect
			(at 11.999976 0 90.001)
			(size 0.2794 2.286)
			(layers "F.Cu" "F.Mask" "F.Paste")
			(net "GND")
		)
		(pad "50" smd rect
			(at 11.999976 -5.727954 90.001)
			(size 0.2794 2.286)
			(layers "F.Cu" "F.Mask" "F.Paste")
			(net "GND")
		)
		(pad "51" smd rect
			(at 12.500102 0 90.001)
			(size 0.2794 2.286)
			(layers "F.Cu" "F.Mask" "F.Paste")
			(net "SMB_HOST_STBY_LVC3_SDA")
		)
		(pad "52" smd rect
			(at 12.500102 -5.727954 90.001)
			(size 0.2794 2.286)
			(layers "F.Cu" "F.Mask" "F.Paste")
			(net "XDP_TDO")
		)
		(pad "53" smd rect
			(at 12.999974 0 90.001)
			(size 0.2794 2.286)
			(layers "F.Cu" "F.Mask" "F.Paste")
			(net "SMB_HOST_STBY_LVC3_SCL")
		)
		(pad "54" smd rect
			(at 12.999974 -5.727954 90.001)
			(size 0.2794 2.286)
			(layers "F.Cu" "F.Mask" "F.Paste")
			(net "XDP_TRST_N")
		)
		(pad "55" smd rect
			(at 13.5001 0 90.001)
			(size 0.2794 2.286)
			(layers "F.Cu" "F.Mask" "F.Paste")
			(net "XDP_PCH_TCK1")
		)
		(pad "56" smd rect
			(at 13.5001 -5.727954 90.001)
			(size 0.2794 2.286)
			(layers "F.Cu" "F.Mask" "F.Paste")
			(net "XDP_TDI")
		)
		(pad "57" smd rect
			(at 13.999972 0 90.001)
			(size 0.2794 2.286)
			(layers "F.Cu" "F.Mask" "F.Paste")
			(net "XDP_CPU_TCK0")
		)
		(pad "58" smd rect
			(at 13.999972 -5.727954 90.001)
			(size 0.2794 2.286)
			(layers "F.Cu" "F.Mask" "F.Paste")
			(net "XDP_TMS")
		)
		(pad "59" smd rect
			(at 14.500098 0 90.001)
			(size 0.2794 2.286)
			(layers "F.Cu" "F.Mask" "F.Paste")
			(net "GND")
		)
		(pad "60" smd rect
			(at 14.500098 -5.727954 90.001)
			(size 0.2794 2.286)
			(layers "F.Cu" "F.Mask" "F.Paste")
			(net "XDP_PRESENT_N")
		)
		(zone
			(layers "F.Cu" "B.Cu" "In1.Cu" "In2.Cu" "In3.Cu" "In4.Cu" "In5.Cu" "In6.Cu"
				"In7.Cu" "In8.Cu" "In9.Cu" "In10.Cu" "In11.Cu" "In12.Cu"
			)
			(hatch none 0.5)
			(connect_pads
				(clearance 0)
			)
			(min_thickness 0.25)
			(keepout
				(tracks not_allowed)
				(vias allowed)
				(pads allowed)
				(copperpour not_allowed)
				(footprints allowed)
			)
			(placement
				(enabled no)
				(sheetname "")
			)
			(fill
				(thermal_gap 0.5)
				(thermal_bridge_width 0.5)
				(island_removal_mode 0)
			)
			(polygon
				(pts
					(arc
						(start 458.22489 -153.035762)
						(mid 456.67549 -153.035762)
						(end 458.22489 -153.035762)
					)
				)
			)
		)
		(zone
			(layers "F.Cu" "B.Cu" "In1.Cu" "In2.Cu" "In3.Cu" "In4.Cu" "In5.Cu" "In6.Cu"
				"In7.Cu" "In8.Cu" "In9.Cu" "In10.Cu" "In11.Cu" "In12.Cu"
			)
			(hatch none 0.5)
			(connect_pads
				(clearance 0)
			)
			(min_thickness 0.25)
			(keepout
				(tracks not_allowed)
				(vias allowed)
				(pads allowed)
				(copperpour not_allowed)
				(footprints allowed)
			)
			(placement
				(enabled no)
				(sheetname "")
			)
			(fill
				(thermal_gap 0.5)
				(thermal_bridge_width 0.5)
				(island_removal_mode 0)
			)
			(polygon
				(pts
					(arc
						(start 458.225144 -132.909818)
						(mid 456.675744 -132.909818)
						(end 458.225144 -132.909818)
					)
				)
			)
		)
	)
)
